#ISCELL
  mstr_misc dns *
  *
#ISCELL
  pure_quanta quanta_title_block_c *
  *
#ISCELL
  standard offpage *
  page224_i1
#CELL
  pure_quanta q_res *
  page224_i101
#ISCELL
  logical_power universal_power *
  page224_i102
#CELL
  pure_quanta q_res *
  page224_i103
#ISCELL
  logical_power universal_power *
  page224_i104
#ISCELL
  standard offpage *
  page224_i105
#CELL
  pure_quanta pca9545apw *
  page224_i106
#ISCELL
  standard offpage *
  page224_i107
#ISCELL
  standard offpage *
  page224_i108
#CELL
  pure_quanta q_res *
  page224_i109
#CELL
  pure_quanta q_res *
  page224_i110
#CELL
  pure_quanta q_res *
  page224_i111
#ISCELL
  standard offpage *
  page224_i112
#ISCELL
  standard offpage *
  page224_i113
#CELL
  pure_quanta q_res *
  page224_i114
#CELL
  pure_quanta q_res *
  page224_i115
#CELL
  pure_quanta q_res *
  page224_i116
#CELL
  pure_quanta q_res *
  page224_i117
#ISCELL
  standard offpage *
  page224_i118
#ISCELL
  standard offpage *
  page224_i119
#ISCELL
  standard offpage *
  page224_i123
#ISCELL
  standard offpage *
  page224_i124
#ISCELL
  standard offpage *
  page224_i125
#CELL
  pure_quanta q_res *
  page224_i13
#CELL
  pure_quanta q_res *
  page224_i130
#CELL
  pure_quanta q_res *
  page224_i131
#CELL
  pure_quanta q_res *
  page224_i132
#CELL
  pure_quanta q_res *
  page224_i133
#ISCELL
  logical_power universal_power *
  page224_i138
#ISCELL
  standard offpage *
  page224_i139
#CELL
  pure_quanta q_res *
  page224_i14
#CELL
  pure_quanta q_res *
  page224_i142
#CELL
  pure_quanta q_res *
  page224_i143
#ISCELL
  logical_power universal_power *
  page224_i15
#CELL
  pure_quanta q_res *
  page224_i16
#ISCELL
  standard offpage *
  page224_i2
#ISCELL
  logical_power universal_power *
  page224_i21
#CELL
  pure_quanta q_cap *
  page224_i22
#ISCELL
  logical_power universal_gnd *
  page224_i23
#ISCELL
  logical_power universal_power *
  page224_i24
#CELL
  pure_quanta q_cap *
  page224_i25
#ISCELL
  logical_power universal_gnd *
  page224_i26
#CELL
  pure_quanta pca9517ad *
  page224_i28
#ISCELL
  logical_power universal_gnd *
  page224_i29
#CELL
  pure_quanta q_res *
  page224_i3
#ISCELL
  logical_power universal_power *
  page224_i31
#ISCELL
  logical_power universal_gnd *
  page224_i32
#CELL
  pure_quanta q_cap *
  page224_i33
#ISCELL
  logical_power universal_power *
  page224_i34
#CELL
  pure_quanta q_cap *
  page224_i35
#ISCELL
  logical_power universal_gnd *
  page224_i36
#CELL
  pure_quanta pca9517ad *
  page224_i37
#ISCELL
  logical_power universal_gnd *
  page224_i38
#ISCELL
  standard offpage *
  page224_i4
#ISCELL
  logical_power universal_power *
  page224_i41
#CELL
  pure_quanta q_res *
  page224_i42
#CELL
  pure_quanta q_res *
  page224_i43
#CELL
  pure_quanta q_res *
  page224_i44
#ISCELL
  standard offpage *
  page224_i46
#ISCELL
  standard offpage *
  page224_i47
#ISCELL
  logical_power universal_power *
  page224_i48
#CELL
  pure_quanta q_res *
  page224_i49
#ISCELL
  standard offpage *
  page224_i5
#CELL
  pure_quanta q_res *
  page224_i50
#CELL
  pure_quanta q_res *
  page224_i51
#ISCELL
  standard offpage *
  page224_i53
#ISCELL
  standard offpage *
  page224_i54
#CELL
  pure_quanta q_res *
  page224_i6
#CELL
  pure_quanta q_res *
  page224_i62
#CELL
  pure_quanta q_res *
  page224_i63
#CELL
  pure_quanta q_res *
  page224_i64
#CELL
  pure_quanta q_res *
  page224_i65
#ISCELL
  logical_power universal_gnd *
  page224_i67
#CELL
  pure_quanta q_cap *
  page224_i68
#ISCELL
  logical_power universal_gnd *
  page224_i69
#ISCELL
  logical_power universal_power *
  page224_i7
#ISCELL
  logical_power universal_power *
  page224_i70
#CELL
  pure_quanta q_res *
  page224_i8
#CELL
  pure_quanta q_res *
  page224_i83
#CELL
  pure_quanta q_res *
  page224_i84
#CELL
  pure_quanta q_res *
  page224_i85
#CELL
  pure_quanta q_res *
  page224_i86
#ISCELL
  logical_power universal_power *
  page224_i87
#ISCELL
  logical_power universal_gnd *
  page224_i88
#ISCELL
  standard offpage *
  page224_i89
#ISCELL
  standard offpage *
  page224_i90
#ISCELL
  standard offpage *
  page224_i91
#ISCELL
  standard offpage *
  page224_i92
#ISCELL
  standard offpage *
  page224_i93
#ISCELL
  standard offpage *
  page224_i95
#ISCELL
  standard offpage *
  page224_i96
#CELL
  pure_quanta q_res *
  page224_i97
#ISCELL
  standard offpage *
  page224_i99
